FILE_TYPE = MULTI_PHYS_TABLE;

PART 'CONN1_10165288101LF'

{========================================================================================}
:VALUE                  | PART_TYPE | MATERIAL | PART_NUMBER    = STANDARD        | LIFECYCLE          | PART_NUMBER   | JEDEC_TYPE       | DESCRIPTION                        | MANUFTR | MANUF_PN         | RD_CMPLS_LVL | CMPLS_LVL | CLASS | DIP_SMD | FROM_PJ       | DATA                     | FP_ECN               | EE_CHECK_LIST | CREATOR | CREATEDAY  | PSL | STATUS | ESD_CDM | ESD_HBM | ESD_MM | MSD | PIN_LENGTH_LONG_PIN | PIN_LENGTH_SHORT_PIN ;
{========================================================================================}
 'CONN1_10165288-101LF' | 'THLF'    | 'IO'     | 'DFHS03FR030'(!) = ''               | ''               | 'DFHS03FR030' |'CON_GUIDE-F1XG'| 'CONN DIP HOUSING 3P 1R FR(H14.7)' | 'APL'   | '10165288-101LF' | 'EP(V1)'     | ''        | 'IO'  | 'DIP'   | 'F0T-BOB-JON' | 'APL_10165288-101LF.pdf' | '10165288-101LF.msg' | ''            | ''      | '20211213' | ''  | ''     | ''      | ''      | ''     | ''  | '158 MILS'          | '158 MILS'          
 'CONN1_10165288-101LF' | 'THLF'    | 'EMPTY'  | 'DFHS03FR030'(!) = ''               | ''               | 'DFHS03FR030' |'CON_GUIDE-F1XG'| 'CONN DIP HOUSING 3P 1R FR(H14.7)' | 'APL'   | '10165288-101LF' | 'EP(V1)'     | ''        | 'IO'  | 'DIP'   | 'F0T-BOB-JON' | 'APL_10165288-101LF.pdf' | '10165288-101LF.msg' | ''            | ''      | '20211213' | ''  | ''     | ''      | ''      | ''     | ''  | '158 MILS'          | '158 MILS'          

END_PART

END.

